(kicad_pcb
	(version 20240108)
	(generator "pcbnew")
	(generator_version "8.0")
	(general
		(thickness 1.62)
		(legacy_teardrops no)
	)
	(paper "A4")
	(title_block
		(title "Jetson Orin Baseboard")
		(date "2025-03-12")
		(rev "1.3.4")
		(company "Antmicro Ltd")
		(comment 1 "www.antmicro.com")
		(comment 9 "footprints 286-290 of 677")
	)
	(layers
		(0 "F.Cu" signal)
		(1 "In1.Cu" signal)
		(2 "In2.Cu" signal)
		(3 "In3.Cu" signal)
		(4 "In4.Cu" jumper)
		(5 "In5.Cu" signal)
		(6 "In6.Cu" signal)
		(31 "B.Cu" signal)
		(32 "B.Adhes" user "B.Adhesive")
		(33 "F.Adhes" user "F.Adhesive")
		(34 "B.Paste" user)
		(35 "F.Paste" user)
		(36 "B.SilkS" user "B.Silkscreen")
		(37 "F.SilkS" user "F.Silkscreen")
		(38 "B.Mask" user)
		(39 "F.Mask" user)
		(40 "Dwgs.User" user "User.Drawings")
		(41 "Cmts.User" user "User.Comments")
		(42 "Eco1.User" user "User.Eco1")
		(43 "Eco2.User" user "User.Eco2")
		(44 "Edge.Cuts" user)
		(45 "Margin" user)
		(46 "B.CrtYd" user "B.Courtyard")
		(47 "F.CrtYd" user "F.Courtyard")
		(48 "B.Fab" user)
		(49 "F.Fab" user)
	)
	(footprint "antmicro-footprints:R_0402_1005Metric"
		(layer "F.Cu")
		(at 95.5 84.65 90)
		(descr "Resistor SMD 0402")
		(tags "resistor SMD 0402")
		(property "Reference" "R67"
			(at -0.725 -2.625 180)
			(layer "F.SilkS")
			(effects
				(font
					(size 0.7 0.7)
					(thickness 0.15)
				)
				(justify left bottom)
			)
		)
		(property "Value" "R_10k_0402"
			(at 0 1.4 90)
			(layer "F.Fab")
			(effects
				(font
					(size 0.7 0.7)
					(thickness 0.15)
				)
				(justify left bottom)
			)
		)
		(property "Footprint" "antmicro-footprints:R_0402_1005Metric"
			(at 0 0 90)
			(layer "F.Fab")
			(hide yes)
			(effects
				(font
					(size 1.27 1.27)
					(thickness 0.15)
				)
			)
		)
		(property "Datasheet" "https://www.bourns.com/docs/product-datasheets/cr.pdf"
			(at 0 0 90)
			(layer "F.Fab")
			(hide yes)
			(effects
				(font
					(size 1.27 1.27)
					(thickness 0.15)
				)
			)
		)
		(property "Author" "Antmicro"
			(at 180.15 -10.85 0)
			(layer "F.Fab")
			(hide yes)
			(effects
				(font
					(size 1 1)
					(thickness 0.15)
				)
			)
		)
		(property "License" "Apache-2.0"
			(at 180.15 -10.85 0)
			(layer "F.Fab")
			(hide yes)
			(effects
				(font
					(size 1 1)
					(thickness 0.15)
				)
			)
		)
		(property "MPN" "CR0402-FX-1002GLF"
			(at 180.15 -10.85 0)
			(layer "F.Fab")
			(hide yes)
			(effects
				(font
					(size 1 1)
					(thickness 0.15)
				)
			)
		)
		(property "Manufacturer" "Bourns"
			(at 180.15 -10.85 0)
			(layer "F.Fab")
			(hide yes)
			(effects
				(font
					(size 1 1)
					(thickness 0.15)
				)
			)
		)
		(property "Tolerance" "1%"
			(at 180.15 -10.85 0)
			(layer "F.Fab")
			(hide yes)
			(effects
				(font
					(size 1 1)
					(thickness 0.15)
				)
			)
		)
		(property "Val" "10k"
			(at 180.15 -10.85 0)
			(layer "F.Fab")
			(hide yes)
			(effects
				(font
					(size 1 1)
					(thickness 0.15)
				)
			)
		)
		(sheetname "CSI")
		(sheetfile "csi.kicad_sch")
		(attr smd)
		(fp_rect
			(start -0.925 -0.47)
			(end 0.925 0.47)
			(stroke
				(width 0.05)
				(type default)
			)
			(fill none)
			(layer "F.CrtYd")
		)
		(fp_rect
			(start -0.5 -0.25)
			(end 0.5 0.25)
			(stroke
				(width 0.15)
				(type solid)
			)
			(fill none)
			(layer "F.Fab")
		)
		(fp_text user "${REFERENCE}"
			(at -0.95 3.168 90)
			(layer "F.Fab")
			(hide yes)
			(effects
				(font
					(size 0.7 0.7)
					(thickness 0.15)
				)
				(justify left bottom)
			)
		)
		(fp_text user "License: Apache-2.0"
			(at -0.95 5.169 90)
			(layer "F.Fab")
			(hide yes)
			(effects
				(font
					(size 0.7 0.7)
					(thickness 0.15)
				)
				(justify left bottom)
			)
		)
		(fp_text user "Author: Antmicro"
			(at -0.95 4.169 90)
			(layer "F.Fab")
			(hide yes)
			(effects
				(font
					(size 0.7 0.7)
					(thickness 0.15)
				)
				(justify left bottom)
			)
		)
		(pad "1" smd roundrect
			(at -0.48 0 90)
			(size 0.59 0.64)
			(layers "F.Cu" "F.Paste" "F.Mask")
			(roundrect_rratio 0.25)
			(net 87 "+3V3")
			(pintype "passive")
		)
		(pad "2" smd roundrect
			(at 0.48 0 90)
			(size 0.59 0.64)
			(layers "F.Cu" "F.Paste" "F.Mask")
			(roundrect_rratio 0.25)
			(net 393 "CSIB_FLG")
			(pintype "passive")
		)
	)
	(footprint "antmicro-footprints:C_0805_2012Metric"
		(layer "F.Cu")
		(at 71.58 88.63)
		(descr "Capacitor SMD 0805")
		(tags "capacitor SMD 0805")
		(property "Reference" "C151"
			(at -1.28 1.8 0)
			(layer "F.SilkS")
			(effects
				(font
					(size 0.7 0.7)
					(thickness 0.15)
				)
				(justify left bottom)
			)
		)
		(property "Value" "C_22u_25V_0805"
			(at -2.055717 1.963152 0)
			(layer "F.Fab")
			(effects
				(font
					(size 0.7 0.7)
					(thickness 0.15)
				)
				(justify left bottom)
			)
		)
		(property "Footprint" "antmicro-footprints:C_0805_2012Metric"
			(at 0 0 0)
			(layer "F.Fab")
			(hide yes)
			(effects
				(font
					(size 1.27 1.27)
					(thickness 0.15)
				)
			)
		)
		(property "Datasheet" "https://product.samsungsem.com/mlcc/CL21A226MAYNNN.do"
			(at 0 0 0)
			(layer "F.Fab")
			(hide yes)
			(effects
				(font
					(size 1.27 1.27)
					(thickness 0.15)
				)
			)
		)
		(property "Author" "Antmicro"
			(at 0 0 0)
			(layer "F.Fab")
			(hide yes)
			(effects
				(font
					(size 1 1)
					(thickness 0.15)
				)
			)
		)
		(property "Dielectric" "X5R"
			(at 0 0 0)
			(layer "F.Fab")
			(hide yes)
			(effects
				(font
					(size 1 1)
					(thickness 0.15)
				)
			)
		)
		(property "License" "Apache-2.0"
			(at 0 0 0)
			(layer "F.Fab")
			(hide yes)
			(effects
				(font
					(size 1 1)
					(thickness 0.15)
				)
			)
		)
		(property "MPN" "CL21A226MAYNNNE"
			(at 0 0 0)
			(layer "F.Fab")
			(hide yes)
			(effects
				(font
					(size 1 1)
					(thickness 0.15)
				)
			)
		)
		(property "Manufacturer" "Samsung Electro-Mechanics"
			(at 0 0 0)
			(layer "F.Fab")
			(hide yes)
			(effects
				(font
					(size 1 1)
					(thickness 0.15)
				)
			)
		)
		(property "Public" "False"
			(at 0 0 0)
			(layer "F.Fab")
			(hide yes)
			(effects
				(font
					(size 1 1)
					(thickness 0.15)
				)
			)
		)
		(property "Val" "22u"
			(at 0 0 0)
			(layer "F.Fab")
			(hide yes)
			(effects
				(font
					(size 1 1)
					(thickness 0.15)
				)
			)
		)
		(property "Voltage" "25V"
			(at 0 0 0)
			(layer "F.Fab")
			(hide yes)
			(effects
				(font
					(size 1 1)
					(thickness 0.15)
				)
			)
		)
		(sheetname "Supply")
		(sheetfile "supply.kicad_sch")
		(attr smd)
		(fp_line
			(start -0.3 -0.7)
			(end 0.3 -0.7)
			(stroke
				(width 0.15)
				(type solid)
			)
			(layer "F.SilkS")
		)
		(fp_line
			(start -0.3 0.7)
			(end 0.3 0.7)
			(stroke
				(width 0.15)
				(type solid)
			)
			(layer "F.SilkS")
		)
		(fp_rect
			(start 1.95 -0.9)
			(end -1.95 0.9)
			(stroke
				(width 0.05)
				(type default)
			)
			(fill none)
			(layer "F.CrtYd")
		)
		(fp_rect
			(start -0.95 -0.675)
			(end 0.95 0.675)
			(stroke
				(width 0.15)
				(type solid)
			)
			(fill none)
			(layer "F.Fab")
		)
		(fp_text user "${REFERENCE}"
			(at -1.9 3.947 0)
			(layer "F.Fab")
			(hide yes)
			(effects
				(font
					(size 0.7 0.7)
					(thickness 0.15)
				)
				(justify left bottom)
			)
		)
		(fp_text user "Author: Antmicro"
			(at -1.9 5.947 0)
			(layer "F.Fab")
			(hide yes)
			(effects
				(font
					(size 0.7 0.7)
					(thickness 0.15)
				)
				(justify left bottom)
			)
		)
		(fp_text user "License: Apache-2.0"
			(at -1.9 4.947 0)
			(layer "F.Fab")
			(hide yes)
			(effects
				(font
					(size 0.7 0.7)
					(thickness 0.15)
				)
				(justify left bottom)
			)
		)
		(pad "1" smd roundrect
			(at -1.1 0)
			(size 1.2 1.3)
			(layers "F.Cu" "F.Paste" "F.Mask")
			(roundrect_rratio 0.25)
			(net 1 "GND")
			(pintype "passive")
		)
		(pad "2" smd roundrect
			(at 1.1 0)
			(size 1.2 1.3)
			(layers "F.Cu" "F.Paste" "F.Mask")
			(roundrect_rratio 0.25)
			(net 115 "VCC")
			(pintype "passive")
		)
	)
	(footprint "antmicro-footprints:LED_0603_1608Metric_G"
		(layer "F.Cu")
		(at 107.6 127.2 90)
		(descr "LED SMD 0603 Green")
		(tags "LED SMD 0603 Green")
		(property "Reference" "D11"
			(at 5.375 0.45 90)
			(layer "F.SilkS")
			(effects
				(font
					(size 0.7 0.7)
					(thickness 0.15)
				)
				(justify right bottom)
			)
		)
		(property "Value" "LED_G_0603_LTST-C190GKT"
			(at -0.001 1.599 90)
			(layer "F.Fab")
			(effects
				(font
					(size 0.7 0.7)
					(thickness 0.15)
				)
				(justify left bottom)
			)
		)
		(property "Footprint" "antmicro-footprints:LED_0603_1608Metric_G"
			(at 0 0 90)
			(layer "F.Fab")
			(hide yes)
			(effects
				(font
					(size 1.27 1.27)
					(thickness 0.15)
				)
			)
		)
		(property "Datasheet" "https://media.digikey.com/pdf/Data%20Sheets/Lite-On%20PDFs/LTST-C190GKT.pdf"
			(at 0 0 90)
			(layer "F.Fab")
			(hide yes)
			(effects
				(font
					(size 1.27 1.27)
					(thickness 0.15)
				)
			)
		)
		(property "Author" "Antmicro"
			(at 234.8 19.6 0)
			(layer "F.Fab")
			(hide yes)
			(effects
				(font
					(size 1 1)
					(thickness 0.15)
				)
			)
		)
		(property "Color" "Green"
			(at 234.8 19.6 0)
			(layer "F.Fab")
			(hide yes)
			(effects
				(font
					(size 1 1)
					(thickness 0.15)
				)
			)
		)
		(property "License" "Apache-2.0"
			(at 234.8 19.6 0)
			(layer "F.Fab")
			(hide yes)
			(effects
				(font
					(size 1 1)
					(thickness 0.15)
				)
			)
		)
		(property "MPN" "LTST-C190GKT"
			(at 234.8 19.6 0)
			(layer "F.Fab")
			(hide yes)
			(effects
				(font
					(size 1 1)
					(thickness 0.15)
				)
			)
		)
		(property "Manufacturer" "Lite-On"
			(at 234.8 19.6 0)
			(layer "F.Fab")
			(hide yes)
			(effects
				(font
					(size 1 1)
					(thickness 0.15)
				)
			)
		)
		(sheetname "USB3")
		(sheetfile "usb3.kicad_sch")
		(attr smd)
		(fp_line
			(start 0.22 -0.35)
			(end -0.22 -0.35)
			(stroke
				(width 0.15)
				(type solid)
			)
			(layer "F.SilkS")
		)
		(fp_line
			(start -1.18 -0.319)
			(end -1.18 0.321)
			(stroke
				(width 0.15)
				(type solid)
			)
			(layer "F.SilkS")
		)
		(fp_line
			(start 0.105328 0.001008)
			(end 0.24 0.001)
			(stroke
				(width 0.1)
				(type solid)
			)
			(layer "F.SilkS")
		)
		(fp_line
			(start -0.094672 0.001008)
			(end 0.105328 -0.198992)
			(stroke
				(width 0.1)
				(type solid)
			)
			(layer "F.SilkS")
		)
		(fp_line
			(start -0.094672 0.001008)
			(end -0.24 0.001008)
			(stroke
				(width 0.1)
				(type solid)
			)
			(layer "F.SilkS")
		)
		(fp_line
			(start 0.105328 0.201008)
			(end 0.105328 -0.198992)
			(stroke
				(width 0.1)
				(type solid)
			)
			(layer "F.SilkS")
		)
		(fp_line
			(start 0.105328 0.201008)
			(end -0.094672 0.001008)
			(stroke
				(width 0.1)
				(type solid)
			)
			(layer "F.SilkS")
		)
		(fp_line
			(start -0.094672 0.201008)
			(end -0.094672 -0.198992)
			(stroke
				(width 0.1)
				(type solid)
			)
			(layer "F.SilkS")
		)
		(fp_line
			(start 0.22 0.35)
			(end -0.22 0.35)
			(stroke
				(width 0.15)
				(type solid)
			)
			(layer "F.SilkS")
		)
		(fp_rect
			(start 1.25 0.65)
			(end -1.25 -0.65)
			(stroke
				(width 0.05)
				(type solid)
			)
			(fill none)
			(layer "F.CrtYd")
		)
		(fp_line
			(start 0.201 -0.202)
			(end -0.101 0)
			(stroke
				(width 0.15)
				(type solid)
			)
			(layer "F.Fab")
		)
		(fp_line
			(start -0.199 -0.202)
			(end -0.199 0.1)
			(stroke
				(width 0.15)
				(type solid)
			)
			(layer "F.Fab")
		)
		(fp_line
			(start 0.599 0)
			(end 0.201 0)
			(stroke
				(width 0.15)
				(type solid)
			)
			(layer "F.Fab")
		)
		(fp_line
			(start 0.201 0)
			(end 0.201 -0.202)
			(stroke
				(width 0.15)
				(type solid)
			)
			(layer "F.Fab")
		)
		(fp_line
			(start -0.101 0)
			(end 0.201 0.2)
			(stroke
				(width 0.15)
				(type solid)
			)
			(layer "F.Fab")
		)
		(fp_line
			(start -0.199 0)
			(end -0.597 0)
			(stroke
				(width 0.15)
				(type solid)
			)
			(layer "F.Fab")
		)
		(fp_line
			(start 0.201 0.2)
			(end 0.201 0)
			(stroke
				(width 0.15)
				(type solid)
			)
			(layer "F.Fab")
		)
		(fp_line
			(start -0.199 0.2)
			(end -0.199 0.1)
			(stroke
				(width 0.15)
				(type solid)
			)
			(layer "F.Fab")
		)
		(fp_rect
			(start 0.848 0.4)
			(end -0.85 -0.402)
			(stroke
				(width 0.15)
				(type solid)
			)
			(fill none)
			(layer "F.Fab")
		)
		(fp_text user "${REFERENCE}"
			(at -1.4224 5.999 90)
			(layer "F.Fab")
			(hide yes)
			(effects
				(font
					(size 0.7 0.7)
					(thickness 0.15)
				)
				(justify left bottom)
			)
		)
		(fp_text user "License: Apache-2.0"
			(at -1.4224 3.599 90)
			(layer "F.Fab")
			(hide yes)
			(effects
				(font
					(size 0.7 0.7)
					(thickness 0.15)
				)
				(justify left bottom)
			)
		)
		(fp_text user "Author: Antmicro"
			(at -1.4224 4.799 90)
			(layer "F.Fab")
			(hide yes)
			(effects
				(font
					(size 0.7 0.7)
					(thickness 0.15)
				)
				(justify left bottom)
			)
		)
		(pad "1" smd roundrect
			(at -0.7 0 270)
			(size 0.8 1)
			(layers "F.Cu" "F.Paste" "F.Mask")
			(roundrect_rratio 0.2)
			(net 1 "GND")
			(pinfunction "C")
			(pintype "passive")
		)
		(pad "2" smd roundrect
			(at 0.7 0 270)
			(size 0.8 1)
			(layers "F.Cu" "F.Paste" "F.Mask")
			(roundrect_rratio 0.2)
			(net 150 "Net-(D11-A)")
			(pinfunction "A")
			(pintype "passive")
		)
	)
	(footprint "antmicro-footprints:R_0402_1005Metric"
		(layer "F.Cu")
		(at 93.92 104.08 -135)
		(descr "Resistor SMD 0402")
		(tags "resistor SMD 0402")
		(property "Reference" "R210"
			(at 0.876812 -1.414214 -135)
			(layer "F.SilkS")
			(effects
				(font
					(size 0.7 0.7)
					(thickness 0.15)
				)
				(justify left bottom)
			)
		)
		(property "Value" "R_499R_0402"
			(at -1.011843 1.772046 -135)
			(layer "F.Fab")
			(effects
				(font
					(size 0.7 0.7)
					(thickness 0.15)
				)
				(justify left bottom)
			)
		)
		(property "Footprint" "antmicro-footprints:R_0402_1005Metric"
			(at 0 0 -135)
			(layer "F.Fab")
			(hide yes)
			(effects
				(font
					(size 1.27 1.27)
					(thickness 0.15)
				)
			)
		)
		(property "Datasheet" "https://www.mouser.com/datasheet/2/54/cr-1858361.pdf"
			(at 0 0 -135)
			(layer "F.Fab")
			(hide yes)
			(effects
				(font
					(size 1.27 1.27)
					(thickness 0.15)
				)
			)
		)
		(property "Author" "Antmicro"
			(at 86.735795 244.087143 0)
			(layer "F.Fab")
			(hide yes)
			(effects
				(font
					(size 1 1)
					(thickness 0.15)
				)
			)
		)
		(property "License" "Apache-2.0"
			(at 86.735795 244.087143 0)
			(layer "F.Fab")
			(hide yes)
			(effects
				(font
					(size 1 1)
					(thickness 0.15)
				)
			)
		)
		(property "MPN" "CR0402-FX-4990GLF"
			(at 86.735795 244.087143 0)
			(layer "F.Fab")
			(hide yes)
			(effects
				(font
					(size 1 1)
					(thickness 0.15)
				)
			)
		)
		(property "Manufacturer" "Bourns"
			(at 86.735795 244.087143 0)
			(layer "F.Fab")
			(hide yes)
			(effects
				(font
					(size 1 1)
					(thickness 0.15)
				)
			)
		)
		(property "Tolerance" "1%"
			(at 86.735795 244.087143 0)
			(layer "F.Fab")
			(hide yes)
			(effects
				(font
					(size 1 1)
					(thickness 0.15)
				)
			)
		)
		(property "Val" "499R"
			(at 86.735795 244.087143 0)
			(layer "F.Fab")
			(hide yes)
			(effects
				(font
					(size 1 1)
					(thickness 0.15)
				)
			)
		)
		(sheetname "HDMI")
		(sheetfile "hdmi.kicad_sch")
		(attr smd)
		(fp_poly
			(pts
				(xy -0.925 -0.47) (xy 0.925 -0.47) (xy 0.925 0.47) (xy -0.925 0.47)
			)
			(stroke
				(width 0.05)
				(type default)
			)
			(fill none)
			(layer "F.CrtYd")
		)
		(fp_poly
			(pts
				(xy -0.5 -0.25) (xy 0.5 -0.25) (xy 0.5 0.25) (xy -0.5 0.25)
			)
			(stroke
				(width 0.15)
				(type solid)
			)
			(fill none)
			(layer "F.Fab")
		)
		(fp_text user "License: Apache-2.0"
			(at -0.949999 5.169 -135)
			(layer "F.Fab")
			(hide yes)
			(effects
				(font
					(size 0.7 0.7)
					(thickness 0.15)
				)
				(justify left bottom)
			)
		)
		(fp_text user "Author: Antmicro"
			(at -0.95 4.169 -135)
			(layer "F.Fab")
			(hide yes)
			(effects
				(font
					(size 0.7 0.7)
					(thickness 0.15)
				)
				(justify left bottom)
			)
		)
		(fp_text user "${REFERENCE}"
			(at -0.95 3.168 -135)
			(layer "F.Fab")
			(hide yes)
			(effects
				(font
					(size 0.7 0.7)
					(thickness 0.15)
				)
				(justify left bottom)
			)
		)
		(pad "1" smd roundrect
			(at -0.48 0 225)
			(size 0.59 0.64)
			(layers "F.Cu" "F.Paste" "F.Mask")
			(roundrect_rratio 0.25)
			(net 623 "Net-(Q2-D)")
			(pintype "passive")
		)
		(pad "2" smd roundrect
			(at 0.48 0 225)
			(size 0.59 0.64)
			(layers "F.Cu" "F.Paste" "F.Mask")
			(roundrect_rratio 0.25)
			(net 492 "/HDMI/HDMI_D2_P")
			(pintype "passive")
		)
	)
	(footprint "antmicro-footprints:R_0402_1005Metric"
		(layer "F.Cu")
		(at 61 121.9)
		(descr "Resistor SMD 0402")
		(tags "resistor SMD 0402")
		(property "Reference" "R188"
			(at -0.035 1.32 0)
			(layer "F.SilkS")
			(effects
				(font
					(size 0.7 0.7)
					(thickness 0.15)
				)
				(justify left bottom)
			)
		)
		(property "Value" "R_10k_0402"
			(at 0 1.4 0)
			(layer "F.Fab")
			(effects
				(font
					(size 0.7 0.7)
					(thickness 0.15)
				)
				(justify left bottom)
			)
		)
		(property "Footprint" "antmicro-footprints:R_0402_1005Metric"
			(at 0 0 0)
			(layer "F.Fab")
			(hide yes)
			(effects
				(font
					(size 1.27 1.27)
					(thickness 0.15)
				)
			)
		)
		(property "Datasheet" "https://www.bourns.com/docs/product-datasheets/cr.pdf"
			(at 0 0 0)
			(layer "F.Fab")
			(hide yes)
			(effects
				(font
					(size 1.27 1.27)
					(thickness 0.15)
				)
			)
		)
		(property "Author" "Antmicro"
			(at 0 0 0)
			(layer "F.Fab")
			(hide yes)
			(effects
				(font
					(size 1 1)
					(thickness 0.15)
				)
			)
		)
		(property "License" "Apache-2.0"
			(at 0 0 0)
			(layer "F.Fab")
			(hide yes)
			(effects
				(font
					(size 1 1)
					(thickness 0.15)
				)
			)
		)
		(property "MPN" "CR0402-FX-1002GLF"
			(at 0 0 0)
			(layer "F.Fab")
			(hide yes)
			(effects
				(font
					(size 1 1)
					(thickness 0.15)
				)
			)
		)
		(property "Manufacturer" "Bourns"
			(at 0 0 0)
			(layer "F.Fab")
			(hide yes)
			(effects
				(font
					(size 1 1)
					(thickness 0.15)
				)
			)
		)
		(property "Tolerance" "1%"
			(at 0 0 0)
			(layer "F.Fab")
			(hide yes)
			(effects
				(font
					(size 1 1)
					(thickness 0.15)
				)
			)
		)
		(property "Val" "10k"
			(at 0 0 0)
			(layer "F.Fab")
			(hide yes)
			(effects
				(font
					(size 1 1)
					(thickness 0.15)
				)
			)
		)
		(sheetname "Supply")
		(sheetfile "supply.kicad_sch")
		(attr smd)
		(fp_rect
			(start -0.925 -0.47)
			(end 0.925 0.47)
			(stroke
				(width 0.05)
				(type default)
			)
			(fill none)
			(layer "F.CrtYd")
		)
		(fp_rect
			(start -0.5 -0.25)
			(end 0.5 0.25)
			(stroke
				(width 0.15)
				(type solid)
			)
			(fill none)
			(layer "F.Fab")
		)
		(fp_text user "Author: Antmicro"
			(at -0.95 4.169 0)
			(layer "F.Fab")
			(hide yes)
			(effects
				(font
					(size 0.7 0.7)
					(thickness 0.15)
				)
				(justify left bottom)
			)
		)
		(fp_text user "License: Apache-2.0"
			(at -0.95 5.169 0)
			(layer "F.Fab")
			(hide yes)
			(effects
				(font
					(size 0.7 0.7)
					(thickness 0.15)
				)
				(justify left bottom)
			)
		)
		(fp_text user "${REFERENCE}"
			(at -0.95 3.168 0)
			(layer "F.Fab")
			(hide yes)
			(effects
				(font
					(size 0.7 0.7)
					(thickness 0.15)
				)
				(justify left bottom)
			)
		)
		(pad "1" smd roundrect
			(at -0.48 0)
			(size 0.59 0.64)
			(layers "F.Cu" "F.Paste" "F.Mask")
			(roundrect_rratio 0.25)
			(net 654 "Net-(D53-A)")
			(pintype "passive")
		)
		(pad "2" smd roundrect
			(at 0.48 0)
			(size 0.59 0.64)
			(layers "F.Cu" "F.Paste" "F.Mask")
			(roundrect_rratio 0.25)
			(net 115 "VCC")
			(pintype "passive")
		)
	)
)
